# S9S_MB_2U (Grand Teton) — schematic netlist excerpt (pin names and nets, part order shuffled) for the footprints in the layout excerpt that follows; sources: Cadence DE-HDL packaged netlist, KiCad conversion of 03242023_DA0F0TMBIJ0_F0T_Motherboard_J_brd_V01_OCP.brd

R3149  Q_RES  1K 1% EMPTY  pkg 0402LF  page 164 : A = P3V3_AUX ; B = PD_SMB_OCP2_HP_ADD2

(kicad_pcb
	(version 20260206)
	(generator "pcbnew")
	(generator_version "10.0")
	(general
		(thickness 1.6)
		(legacy_teardrops no)
	)
	(paper "A4")
	(title_block
		(title "03242023_DA0F0TMBIJ0_F0T_Motherboard_J_brd_V01_OCP.brd")
		(comment 1 "Grand Teton / footprints 3348-3348 of 6105")
	)
	(layers
		(0 "F.Cu" signal "TOP")
		(4 "In1.Cu" signal "GND")
		(6 "In2.Cu" signal "IN1")
		(8 "In3.Cu" signal "GND1")
		(10 "In4.Cu" signal "IN2")
		(12 "In5.Cu" signal "GND2")
		(14 "In6.Cu" signal "IN3")
		(16 "In7.Cu" signal "GND3")
		(18 "In8.Cu" signal "VCC")
		(20 "In9.Cu" signal "VCC1")
		(22 "In10.Cu" signal "GND4")
		(24 "In11.Cu" signal "IN4")
		(26 "In12.Cu" signal "GND5")
		(28 "In13.Cu" signal "IN5")
		(30 "In14.Cu" signal "GND6")
		(32 "In15.Cu" signal "IN6")
		(34 "In16.Cu" signal "GND7")
		(2 "B.Cu" signal "BOTTOM")
		(9 "F.Adhes" user "F.Adhesive")
		(11 "B.Adhes" user "B.Adhesive")
		(13 "F.Paste" user "Package Geometry/Pastemask Top")
		(15 "B.Paste" user "Package Geometry/Pastemask Bottom")
		(5 "F.SilkS" user "Ref Des/Silkscreen Top")
		(7 "B.SilkS" user "Ref Des/Silkscreen Bottom")
		(1 "F.Mask" user "Board Geometry/Soldermask Top")
		(3 "B.Mask" user "Board Geometry/Soldermask Bottom")
		(17 "Dwgs.User" user "User.Drawings")
		(19 "Cmts.User" user "User.Comments")
		(21 "Eco1.User" user "User.Eco1")
		(23 "Eco2.User" user "User.Eco2")
		(25 "Edge.Cuts" user "Board Geometry/Outline")
		(27 "Margin" user)
		(31 "F.CrtYd" user "Package Geometry/Place Bound Top")
		(29 "B.CrtYd" user "Package Geometry/Place Bound Bottom")
		(35 "F.Fab" user "Ref Des/Assembly Top")
		(33 "B.Fab" user "Ref Des/Assembly Bottom")
	)
	(footprint ""
		(layer "F.Cu")
		(at 134.2136 -124.234448)
		(property "Reference" "R3149"
			(at 0 0 0)
			(layer "F.SilkS")
			(hide yes)
			(effects
				(font
					(size 1.27 1.27)
				)
			)
		)
		(property "Value" ""
			(at 0 0 0)
			(layer "F.Fab")
			(effects
				(font
					(size 1.27 1.27)
				)
			)
		)
		(duplicate_pad_numbers_are_jumpers no)
		(fp_line
			(start -0.7874 -0.4064)
			(end 0.7874 -0.4064)
			(stroke
				(width 0.1524)
				(type default)
			)
			(layer "F.SilkS")
		)
		(fp_line
			(start -0.7874 0.4064)
			(end -0.7874 -0.4064)
			(stroke
				(width 0.1524)
				(type default)
			)
			(layer "F.SilkS")
		)
		(fp_line
			(start 0.7874 -0.4064)
			(end 0.7874 0.4064)
			(stroke
				(width 0.1524)
				(type default)
			)
			(layer "F.SilkS")
		)
		(fp_line
			(start 0.7874 0.4064)
			(end -0.7874 0.4064)
			(stroke
				(width 0.1524)
				(type default)
			)
			(layer "F.SilkS")
		)
		(fp_line
			(start -0.67945 -0.305054)
			(end -0.12065 -0.305054)
			(stroke
				(width 0.1)
				(type default)
			)
			(layer "F.Fab")
		)
		(fp_line
			(start -0.67945 0.3048)
			(end -0.67945 -0.305054)
			(stroke
				(width 0.1)
				(type default)
			)
			(layer "F.Fab")
		)
		(fp_line
			(start -0.12065 -0.305054)
			(end -0.12065 -0.2794)
			(stroke
				(width 0.1)
				(type default)
			)
			(layer "F.Fab")
		)
		(fp_line
			(start -0.12065 -0.2794)
			(end 0.12065 -0.2794)
			(stroke
				(width 0.1)
				(type default)
			)
			(layer "F.Fab")
		)
		(fp_line
			(start -0.12065 0.2794)
			(end -0.12065 0.3048)
			(stroke
				(width 0.1)
				(type default)
			)
			(layer "F.Fab")
		)
		(fp_line
			(start -0.12065 0.3048)
			(end -0.67945 0.3048)
			(stroke
				(width 0.1)
				(type default)
			)
			(layer "F.Fab")
		)
		(fp_line
			(start 0.120396 0.2794)
			(end -0.12065 0.2794)
			(stroke
				(width 0.1)
				(type default)
			)
			(layer "F.Fab")
		)
		(fp_line
			(start 0.120396 0.3048)
			(end 0.120396 0.2794)
			(stroke
				(width 0.1)
				(type default)
			)
			(layer "F.Fab")
		)
		(fp_line
			(start 0.12065 -0.3048)
			(end 0.67945 -0.3048)
			(stroke
				(width 0.1)
				(type default)
			)
			(layer "F.Fab")
		)
		(fp_line
			(start 0.12065 -0.2794)
			(end 0.12065 -0.3048)
			(stroke
				(width 0.1)
				(type default)
			)
			(layer "F.Fab")
		)
		(fp_line
			(start 0.67945 -0.3048)
			(end 0.67945 0.3048)
			(stroke
				(width 0.1)
				(type default)
			)
			(layer "F.Fab")
		)
		(fp_line
			(start 0.67945 0.3048)
			(end 0.120396 0.3048)
			(stroke
				(width 0.1)
				(type default)
			)
			(layer "F.Fab")
		)
		(pad "1" smd circle
			(at -0.40005 0)
			(size 0 0)
			(layers "F.Cu" "F.Mask" "F.Paste")
			(net "P3V3_AUX")
		)
		(pad "2" smd circle
			(at 0.40005 0)
			(size 0 0)
			(layers "F.Cu" "F.Mask" "F.Paste")
			(net "PD_SMB_OCP2_HP_ADD2")
		)
	)
)
